(kicad_pcb
	(version 20260206)
	(generator "pcbnew")
	(generator_version "10.0")
	(general
		(thickness 1.6)
		(legacy_teardrops no)
	)
	(paper "A4")
	(title_block
		(title "v1-chassis-manager — T6M_CM_d_v01_1031_1645.brd")
		(comment 1 "Open CloudServer (Microsoft) / footprints 281-288 of 2512")
	)
	(layers
		(0 "F.Cu" signal "TOP")
		(4 "In1.Cu" signal "GND1")
		(6 "In2.Cu" signal "IN1")
		(8 "In3.Cu" signal "VCC1")
		(10 "In4.Cu" signal "VCC2")
		(12 "In5.Cu" signal "GND2")
		(14 "In6.Cu" signal "IN2")
		(16 "In7.Cu" signal "IN3")
		(18 "In8.Cu" signal "GND3")
		(2 "B.Cu" signal "BOTTOM")
		(9 "F.Adhes" user "F.Adhesive")
		(11 "B.Adhes" user "B.Adhesive")
		(13 "F.Paste" user "Package Geometry/Pastemask Top")
		(15 "B.Paste" user "Package Geometry/Pastemask Bottom")
		(5 "F.SilkS" user "Ref Des/Silkscreen Top")
		(7 "B.SilkS" user "Ref Des/Silkscreen Bottom")
		(1 "F.Mask" user "Board Geometry/Soldermask Top")
		(3 "B.Mask" user "Board Geometry/Soldermask Bottom")
		(17 "Dwgs.User" user "User.Drawings")
		(19 "Cmts.User" user "User.Comments")
		(21 "Eco1.User" user "User.Eco1")
		(23 "Eco2.User" user "User.Eco2")
		(25 "Edge.Cuts" user "Board Geometry/Outline")
		(27 "Margin" user)
		(31 "F.CrtYd" user "Package Geometry/Place Bound Top")
		(29 "B.CrtYd" user "Package Geometry/Place Bound Bottom")
		(35 "F.Fab" user "Ref Des/Assembly Top")
		(33 "B.Fab" user "Ref Des/Assembly Bottom")
	)
	(footprint ""
		(layer "F.Cu")
		(at 110.727998 -29.030422 -90)
		(property "Reference" "C859"
			(at -2.0955 -0.369062 90)
			(unlocked yes)
			(layer "F.SilkS")
			(effects
				(font
					(size 0.7874 0.5842)
					(thickness 0.1524)
				)
				(justify left)
			)
		)
		(property "Value" ""
			(at 0 0 270)
			(layer "F.Fab")
			(effects
				(font
					(size 1.27 1.27)
				)
			)
		)
		(duplicate_pad_numbers_are_jumpers no)
		(fp_line
			(start -1.905 0.8636)
			(end -1.905 -0.8636)
			(stroke
				(width 0.1524)
				(type default)
			)
			(layer "F.SilkS")
		)
		(fp_line
			(start 1.905 0.8636)
			(end -1.905 0.8636)
			(stroke
				(width 0.1524)
				(type default)
			)
			(layer "F.SilkS")
		)
		(fp_line
			(start 0 0.8382)
			(end 0 -0.8382)
			(stroke
				(width 0.1524)
				(type default)
			)
			(layer "F.SilkS")
		)
		(fp_line
			(start -1.905 -0.8636)
			(end 1.905 -0.8636)
			(stroke
				(width 0.1524)
				(type default)
			)
			(layer "F.SilkS")
		)
		(fp_line
			(start 1.905 -0.8636)
			(end 1.905 0.8636)
			(stroke
				(width 0.1524)
				(type default)
			)
			(layer "F.SilkS")
		)
		(fp_rect
			(start -1.524 0.7366)
			(end 1.524 -0.7366)
			(stroke
				(width 0)
				(type default)
			)
			(fill no)
			(layer "F.CrtYd")
		)
		(pad "1" smd rect
			(at 0.94996 0 270)
			(size 1.1176 1.3716)
			(layers "F.Cu" "F.Mask" "F.Paste")
			(net "PV_VTT_DDR_NODE1")
		)
		(pad "2" smd rect
			(at -0.94996 0 270)
			(size 1.1176 1.3716)
			(layers "F.Cu" "F.Mask" "F.Paste")
			(net "GND")
		)
	)
	(footprint ""
		(layer "F.Cu")
		(at 51.310286 -119.368062 180)
		(property "Reference" "C247"
			(at 7.234428 -0.17526 0)
			(unlocked yes)
			(layer "F.SilkS")
			(effects
				(font
					(size 0.7874 0.5842)
					(thickness 0.1524)
				)
				(justify left)
			)
		)
		(property "Value" ""
			(at 0 0 180)
			(layer "F.Fab")
			(effects
				(font
					(size 1.27 1.27)
				)
			)
		)
		(duplicate_pad_numbers_are_jumpers no)
		(fp_line
			(start 0.7874 0.4064)
			(end -0.7874 0.4064)
			(stroke
				(width 0.1524)
				(type default)
			)
			(layer "F.SilkS")
		)
		(fp_line
			(start 0.7874 -0.4064)
			(end 0.7874 0.4064)
			(stroke
				(width 0.1524)
				(type default)
			)
			(layer "F.SilkS")
		)
		(fp_line
			(start 0 0.381)
			(end 0 -0.381)
			(stroke
				(width 0.1524)
				(type default)
			)
			(layer "F.SilkS")
		)
		(fp_line
			(start -0.7874 0.4064)
			(end -0.7874 -0.4064)
			(stroke
				(width 0.1524)
				(type default)
			)
			(layer "F.SilkS")
		)
		(fp_line
			(start -0.7874 -0.4064)
			(end 0.7874 -0.4064)
			(stroke
				(width 0.1524)
				(type default)
			)
			(layer "F.SilkS")
		)
		(fp_poly
			(pts
				(xy -0.5334 0.254) (xy -0.635 0.254) (xy -0.635 0.2286) (xy -0.635 -0.254) (xy -0.5334 -0.254) (xy -0.5334 -0.2794)
				(xy 0.5334 -0.2794) (xy 0.5334 -0.254) (xy 0.635 -0.254) (xy 0.635 0.254) (xy 0.5334 0.254) (xy 0.5334 0.2794)
				(xy -0.508 0.2794) (xy -0.5334 0.2794)
			)
			(stroke
				(width 0)
				(type default)
			)
			(fill no)
			(layer "F.CrtYd")
		)
		(pad "1" smd rect
			(at 0.40005 0 180)
			(size 0.4572 0.508)
			(layers "F.Cu" "F.Mask" "F.Paste")
			(net "GND")
		)
		(pad "2" smd rect
			(at -0.40005 0 180)
			(size 0.4572 0.508)
			(layers "F.Cu" "F.Mask" "F.Paste")
			(net "BMC_NODE1_OSC1_VDD")
		)
	)
	(footprint ""
		(layer "F.Cu")
		(at 164.905944 -93.840808 -90)
		(property "Reference" "R524"
			(at 1.224788 4.22402 90)
			(unlocked yes)
			(layer "F.SilkS")
			(effects
				(font
					(size 0.7874 0.5842)
					(thickness 0.1524)
				)
				(justify left)
			)
		)
		(property "Value" ""
			(at 0 0 270)
			(layer "F.Fab")
			(effects
				(font
					(size 1.27 1.27)
				)
			)
		)
		(duplicate_pad_numbers_are_jumpers no)
		(fp_line
			(start -0.7874 0.4064)
			(end -0.7874 -0.4064)
			(stroke
				(width 0.1524)
				(type default)
			)
			(layer "F.SilkS")
		)
		(fp_line
			(start 0.7874 0.4064)
			(end -0.7874 0.4064)
			(stroke
				(width 0.1524)
				(type default)
			)
			(layer "F.SilkS")
		)
		(fp_line
			(start -0.7874 -0.4064)
			(end 0.7874 -0.4064)
			(stroke
				(width 0.1524)
				(type default)
			)
			(layer "F.SilkS")
		)
		(fp_line
			(start 0.7874 -0.4064)
			(end 0.7874 0.4064)
			(stroke
				(width 0.1524)
				(type default)
			)
			(layer "F.SilkS")
		)
		(fp_poly
			(pts
				(xy -0.508 0.2794) (xy -0.508 0.2286) (xy -0.635 0.2286) (xy -0.635 -0.254) (xy -0.5334 -0.254)
				(xy -0.5334 -0.2794) (xy 0.5334 -0.2794) (xy 0.5334 -0.254) (xy 0.635 -0.254) (xy 0.635 0.254) (xy 0.5334 0.254)
				(xy 0.5334 0.2794)
			)
			(stroke
				(width 0)
				(type default)
			)
			(fill no)
			(layer "F.CrtYd")
		)
		(pad "1" smd rect
			(at 0.40005 0 270)
			(size 0.4572 0.508)
			(layers "F.Cu" "F.Mask" "F.Paste")
			(net "SPI_USB_NODE1_SO")
		)
		(pad "2" smd rect
			(at -0.40005 0 270)
			(size 0.4572 0.508)
			(layers "F.Cu" "F.Mask" "F.Paste")
			(net "SPI_USB_NODE1_R_SO")
		)
	)
	(footprint ""
		(layer "F.Cu")
		(at 50.90668 -94.920054 180)
		(property "Reference" "C136"
			(at 1.709928 -1.066546 0)
			(unlocked yes)
			(layer "F.SilkS")
			(effects
				(font
					(size 0.7874 0.5842)
					(thickness 0.1524)
				)
				(justify left)
			)
		)
		(property "Value" ""
			(at 0 0 180)
			(layer "F.Fab")
			(effects
				(font
					(size 1.27 1.27)
				)
			)
		)
		(duplicate_pad_numbers_are_jumpers no)
		(fp_line
			(start 0.7874 0.4064)
			(end -0.7874 0.4064)
			(stroke
				(width 0.1524)
				(type default)
			)
			(layer "F.SilkS")
		)
		(fp_line
			(start 0.7874 -0.4064)
			(end 0.7874 0.4064)
			(stroke
				(width 0.1524)
				(type default)
			)
			(layer "F.SilkS")
		)
		(fp_line
			(start 0 0.381)
			(end 0 -0.381)
			(stroke
				(width 0.1524)
				(type default)
			)
			(layer "F.SilkS")
		)
		(fp_line
			(start -0.7874 0.4064)
			(end -0.7874 -0.4064)
			(stroke
				(width 0.1524)
				(type default)
			)
			(layer "F.SilkS")
		)
		(fp_line
			(start -0.7874 -0.4064)
			(end 0.7874 -0.4064)
			(stroke
				(width 0.1524)
				(type default)
			)
			(layer "F.SilkS")
		)
		(fp_poly
			(pts
				(xy -0.5334 0.254) (xy -0.635 0.254) (xy -0.635 0.2286) (xy -0.635 -0.254) (xy -0.5334 -0.254) (xy -0.5334 -0.2794)
				(xy 0.5334 -0.2794) (xy 0.5334 -0.254) (xy 0.635 -0.254) (xy 0.635 0.254) (xy 0.5334 0.254) (xy 0.5334 0.2794)
				(xy -0.508 0.2794) (xy -0.5334 0.2794)
			)
			(stroke
				(width 0)
				(type default)
			)
			(fill no)
			(layer "F.CrtYd")
		)
		(pad "1" smd rect
			(at 0.40005 0 180)
			(size 0.4572 0.508)
			(layers "F.Cu" "F.Mask" "F.Paste")
			(net "P3V3_NODE1")
		)
		(pad "2" smd rect
			(at -0.40005 0 180)
			(size 0.4572 0.508)
			(layers "F.Cu" "F.Mask" "F.Paste")
			(net "GND")
		)
	)
	(footprint ""
		(layer "F.Cu")
		(at 58.869326 -155.710382)
		(property "Reference" "U36"
			(at -3.258312 1.102868 90)
			(unlocked yes)
			(layer "F.SilkS")
			(effects
				(font
					(size 0.7874 0.5842)
					(thickness 0.1524)
				)
				(justify left)
			)
		)
		(property "Value" ""
			(at 0 0 0)
			(layer "F.Fab")
			(effects
				(font
					(size 1.27 1.27)
				)
			)
		)
		(duplicate_pad_numbers_are_jumpers no)
		(fp_line
			(start -2.5146 -1.4224)
			(end 2.5146 -1.4224)
			(stroke
				(width 0.1524)
				(type default)
			)
			(layer "F.SilkS")
		)
		(fp_line
			(start -2.5146 -0.4572)
			(end -2.5146 -1.4224)
			(stroke
				(width 0.1524)
				(type default)
			)
			(layer "F.SilkS")
		)
		(fp_line
			(start -2.5146 0.4572)
			(end -2.0574 0)
			(stroke
				(width 0.1524)
				(type default)
			)
			(layer "F.SilkS")
		)
		(fp_line
			(start -2.5146 1.4224)
			(end -2.5146 0.4572)
			(stroke
				(width 0.1524)
				(type default)
			)
			(layer "F.SilkS")
		)
		(fp_line
			(start -2.0574 0)
			(end -2.5146 -0.4572)
			(stroke
				(width 0.1524)
				(type default)
			)
			(layer "F.SilkS")
		)
		(fp_line
			(start 2.5146 -1.4224)
			(end 2.5146 1.4224)
			(stroke
				(width 0.1524)
				(type default)
			)
			(layer "F.SilkS")
		)
		(fp_line
			(start 2.5146 1.4224)
			(end -2.5146 1.4224)
			(stroke
				(width 0.1524)
				(type default)
			)
			(layer "F.SilkS")
		)
		(fp_circle
			(center -1.905 0.889)
			(end -1.651 0.889)
			(stroke
				(width 0.1524)
				(type default)
			)
			(fill no)
			(layer "F.SilkS")
		)
		(fp_poly
			(pts
				(xy -2.1844 3.5052) (xy -2.1844 2.0066) (xy -2.5146 2.0066) (xy -2.5146 -2.0066) (xy -2.1844 -2.0066)
				(xy -2.1844 -3.5052) (xy 2.1844 -3.5052) (xy 2.1844 -2.0066) (xy 2.5146 -2.0066) (xy 2.5146 2.0066)
				(xy 2.1844 2.0066) (xy 2.1844 3.5052)
			)
			(stroke
				(width 0)
				(type default)
			)
			(fill no)
			(layer "F.CrtYd")
		)
		(pad "1" smd rect
			(at -1.905 2.6416)
			(size 0.5588 1.7272)
			(layers "F.Cu" "F.Mask" "F.Paste")
			(net "LAN1_NVM_CS_N_R")
		)
		(pad "2" smd rect
			(at -0.635 2.6416)
			(size 0.5588 1.7272)
			(layers "F.Cu" "F.Mask" "F.Paste")
			(net "LAN1_NVM_SO_R")
		)
		(pad "3" smd rect
			(at 0.635 2.6416)
			(size 0.5588 1.7272)
			(layers "F.Cu" "F.Mask" "F.Paste")
			(net "LAN1_NVM_WP_N")
		)
		(pad "4" smd rect
			(at 1.905 2.6416)
			(size 0.5588 1.7272)
			(layers "F.Cu" "F.Mask" "F.Paste")
			(net "GND")
		)
		(pad "5" smd rect
			(at 1.905 -2.6416)
			(size 0.5588 1.7272)
			(layers "F.Cu" "F.Mask" "F.Paste")
			(net "LAN1_NVM_SI_R")
		)
		(pad "6" smd rect
			(at 0.635 -2.6416)
			(size 0.5588 1.7272)
			(layers "F.Cu" "F.Mask" "F.Paste")
			(net "LAN1_NVM_SK_R")
		)
		(pad "7" smd rect
			(at -0.635 -2.6416)
			(size 0.5588 1.7272)
			(layers "F.Cu" "F.Mask" "F.Paste")
			(net "LAN1_NVM_HOLD_N")
		)
		(pad "8" smd rect
			(at -1.905 -2.6416)
			(size 0.5588 1.7272)
			(layers "F.Cu" "F.Mask" "F.Paste")
			(net "P3V3_NODE1")
		)
	)
	(footprint ""
		(layer "F.Cu")
		(at 64.069722 -161.722816 -90)
		(property "Reference" "C845"
			(at 1.128014 -8.378444 90)
			(unlocked yes)
			(layer "F.SilkS")
			(effects
				(font
					(size 0.7874 0.5842)
					(thickness 0.1524)
				)
				(justify left)
			)
		)
		(property "Value" ""
			(at 0 0 270)
			(layer "F.Fab")
			(effects
				(font
					(size 1.27 1.27)
				)
			)
		)
		(duplicate_pad_numbers_are_jumpers no)
		(fp_line
			(start -1.905 0.8636)
			(end -1.905 -0.8636)
			(stroke
				(width 0.1524)
				(type default)
			)
			(layer "F.SilkS")
		)
		(fp_line
			(start 1.905 0.8636)
			(end -1.905 0.8636)
			(stroke
				(width 0.1524)
				(type default)
			)
			(layer "F.SilkS")
		)
		(fp_line
			(start 0 0.8382)
			(end 0 -0.8382)
			(stroke
				(width 0.1524)
				(type default)
			)
			(layer "F.SilkS")
		)
		(fp_line
			(start -1.905 -0.8636)
			(end 1.905 -0.8636)
			(stroke
				(width 0.1524)
				(type default)
			)
			(layer "F.SilkS")
		)
		(fp_line
			(start 1.905 -0.8636)
			(end 1.905 0.8636)
			(stroke
				(width 0.1524)
				(type default)
			)
			(layer "F.SilkS")
		)
		(fp_rect
			(start -1.524 0.7366)
			(end 1.524 -0.7366)
			(stroke
				(width 0)
				(type default)
			)
			(fill no)
			(layer "F.CrtYd")
		)
		(pad "1" smd rect
			(at 0.94996 0 270)
			(size 1.1176 1.3716)
			(layers "F.Cu" "F.Mask" "F.Paste")
			(net "FM_CPLD_NODE1_P5V_EN_LV")
		)
		(pad "2" smd rect
			(at -0.94996 0 270)
			(size 1.1176 1.3716)
			(layers "F.Cu" "F.Mask" "F.Paste")
			(net "P5V_NODE1")
		)
	)
	(footprint ""
		(layer "F.Cu")
		(at 43.80357 -186.5249 90)
		(property "Reference" "R1007"
			(at 2.494788 0.24257 90)
			(unlocked yes)
			(layer "F.SilkS")
			(effects
				(font
					(size 0.7874 0.5842)
					(thickness 0.1524)
				)
				(justify left)
			)
		)
		(property "Value" ""
			(at 0 0 90)
			(layer "F.Fab")
			(effects
				(font
					(size 1.27 1.27)
				)
			)
		)
		(duplicate_pad_numbers_are_jumpers no)
		(fp_line
			(start 0.7874 -0.4064)
			(end 0.7874 0.4064)
			(stroke
				(width 0.1524)
				(type default)
			)
			(layer "F.SilkS")
		)
		(fp_line
			(start -0.7874 -0.4064)
			(end 0.7874 -0.4064)
			(stroke
				(width 0.1524)
				(type default)
			)
			(layer "F.SilkS")
		)
		(fp_line
			(start 0.7874 0.4064)
			(end -0.7874 0.4064)
			(stroke
				(width 0.1524)
				(type default)
			)
			(layer "F.SilkS")
		)
		(fp_line
			(start -0.7874 0.4064)
			(end -0.7874 -0.4064)
			(stroke
				(width 0.1524)
				(type default)
			)
			(layer "F.SilkS")
		)
		(fp_poly
			(pts
				(xy -0.508 0.2794) (xy -0.508 0.2286) (xy -0.635 0.2286) (xy -0.635 -0.254) (xy -0.5334 -0.254)
				(xy -0.5334 -0.2794) (xy 0.5334 -0.2794) (xy 0.5334 -0.254) (xy 0.635 -0.254) (xy 0.635 0.254) (xy 0.5334 0.254)
				(xy 0.5334 0.2794)
			)
			(stroke
				(width 0)
				(type default)
			)
			(fill no)
			(layer "F.CrtYd")
		)
		(pad "1" smd rect
			(at 0.40005 0 90)
			(size 0.4572 0.508)
			(layers "F.Cu" "F.Mask" "F.Paste")
			(net "P12V_PDB")
		)
		(pad "2" smd rect
			(at -0.40005 0 90)
			(size 0.4572 0.508)
			(layers "F.Cu" "F.Mask" "F.Paste")
			(net "MATE_N")
		)
	)
	(footprint ""
		(layer "F.Cu")
		(at 52.17414 -166.43985 90)
		(property "Reference" "R563"
			(at -130.36804 -3.432048 90)
			(unlocked yes)
			(layer "F.SilkS")
			(effects
				(font
					(size 0.7874 0.5842)
					(thickness 0.1524)
				)
				(justify left)
			)
		)
		(property "Value" ""
			(at 0 0 90)
			(layer "F.Fab")
			(effects
				(font
					(size 1.27 1.27)
				)
			)
		)
		(duplicate_pad_numbers_are_jumpers no)
		(fp_line
			(start 0.7874 -0.4064)
			(end 0.7874 0.4064)
			(stroke
				(width 0.1524)
				(type default)
			)
			(layer "F.SilkS")
		)
		(fp_line
			(start -0.7874 -0.4064)
			(end 0.7874 -0.4064)
			(stroke
				(width 0.1524)
				(type default)
			)
			(layer "F.SilkS")
		)
		(fp_line
			(start 0.7874 0.4064)
			(end -0.7874 0.4064)
			(stroke
				(width 0.1524)
				(type default)
			)
			(layer "F.SilkS")
		)
		(fp_line
			(start -0.7874 0.4064)
			(end -0.7874 -0.4064)
			(stroke
				(width 0.1524)
				(type default)
			)
			(layer "F.SilkS")
		)
		(fp_poly
			(pts
				(xy -0.508 0.2794) (xy -0.508 0.2286) (xy -0.635 0.2286) (xy -0.635 -0.254) (xy -0.5334 -0.254)
				(xy -0.5334 -0.2794) (xy 0.5334 -0.2794) (xy 0.5334 -0.254) (xy 0.635 -0.254) (xy 0.635 0.254) (xy 0.5334 0.254)
				(xy 0.5334 0.2794)
			)
			(stroke
				(width 0)
				(type default)
			)
			(fill no)
			(layer "F.CrtYd")
		)
		(pad "1" smd rect
			(at 0.40005 0 90)
			(size 0.4572 0.508)
			(layers "F.Cu" "F.Mask" "F.Paste")
			(net "SMB_PCH_SCL")
		)
		(pad "2" smd rect
			(at -0.40005 0 90)
			(size 0.4572 0.508)
			(layers "F.Cu" "F.Mask" "F.Paste")
			(net "SMB_LAN1_CLK")
		)
	)
)
